# BASEBOARD_FAB2 (Tioga Pass) — schematic netlist excerpt (pin names and nets, part order shuffled) for the footprints in the layout excerpt that follows; sources: Cadence DE-HDL packaged netlist, KiCad conversion of Wiwynn_Tioga_Pass_MB.brd

R4D18  RES  42.2 1.0% EMPTY  pkg 0402  page 103 : A = CLK_100M_CPU0_BCLK1_DN ; B = GND
RT15  RES  0 5.0% CHIP  pkg 0603  page 207 : A = VR_PVCCIN_CPU1_PH1_BOOT ; B = VR_PVCCIN_CPU1_PH1_BOOT_R
C4G7  CAP  1000PF 50V 10% EMPTY  pkg 0402LF  page 233 : A = FM_PVPP_CPU1_EN ; B = AGND_PVPP_GHJ

(kicad_pcb
	(version 20260206)
	(generator "pcbnew")
	(generator_version "10.0")
	(general
		(thickness 1.6)
		(legacy_teardrops no)
	)
	(paper "A4")
	(title_block
		(title "Wiwynn_Tioga_Pass_MB.brd")
		(comment 1 "Tioga Pass / footprints 2085-2087 of 4770")
	)
	(layers
		(0 "F.Cu" signal "TOP")
		(4 "In1.Cu" signal "L2GND")
		(6 "In2.Cu" signal "L3")
		(8 "In3.Cu" signal "L4GND")
		(10 "In4.Cu" signal "L5")
		(12 "In5.Cu" signal "L6GND")
		(14 "In6.Cu" signal "L7VCC")
		(16 "In7.Cu" signal "L8VCC")
		(18 "In8.Cu" signal "L9GND")
		(20 "In9.Cu" signal "L10")
		(22 "In10.Cu" signal "L11GND")
		(24 "In11.Cu" signal "L12")
		(26 "In12.Cu" signal "L13GND")
		(2 "B.Cu" signal "BOTTOM")
		(9 "F.Adhes" user "F.Adhesive")
		(11 "B.Adhes" user "B.Adhesive")
		(13 "F.Paste" user "Package Geometry/Pastemask Top")
		(15 "B.Paste" user "Package Geometry/Pastemask Bottom")
		(5 "F.SilkS" user "Ref Des/Silkscreen Top")
		(7 "B.SilkS" user "Ref Des/Silkscreen Bottom")
		(1 "F.Mask" user "Board Geometry/Soldermask Top")
		(3 "B.Mask" user "Board Geometry/Soldermask Bottom")
		(17 "Dwgs.User" user "User.Drawings")
		(19 "Cmts.User" user "User.Comments")
		(21 "Eco1.User" user "User.Eco1")
		(23 "Eco2.User" user "User.Eco2")
		(25 "Edge.Cuts" user "Board Geometry/Outline")
		(27 "Margin" user)
		(31 "F.CrtYd" user "Package Geometry/Place Bound Top")
		(29 "B.CrtYd" user "Package Geometry/Place Bound Bottom")
		(35 "F.Fab" user "Ref Des/Assembly Top")
		(33 "B.Fab" user "Ref Des/Assembly Bottom")
	)
	(footprint ""
		(layer "F.Cu")
		(at 27.559 -57.785 90)
		(property "Reference" "RT15"
			(at 1.01473 0.656336 0)
			(unlocked yes)
			(layer "F.SilkS")
			(effects
				(font
					(size 0.4064 0.254)
					(thickness 0.1524)
				)
			)
		)
		(property "Value" ""
			(at 0 0 90)
			(layer "F.Fab")
			(effects
				(font
					(size 1.27 1.27)
				)
			)
		)
		(duplicate_pad_numbers_are_jumpers no)
		(fp_poly
			(pts
				(xy -0.4953 -0.2032) (xy 0.4953 -0.2032) (xy 0.4953 1.6002) (xy -0.4953 1.6002)
			)
			(stroke
				(width 0)
				(type default)
			)
			(fill no)
			(layer "F.CrtYd")
		)
		(fp_line
			(start 0.4953 -0.2032)
			(end 0.4953 1.6002)
			(stroke
				(width 0.1)
				(type default)
			)
			(layer "F.Fab")
		)
		(fp_line
			(start -0.4953 -0.2032)
			(end 0.4953 -0.2032)
			(stroke
				(width 0.1)
				(type default)
			)
			(layer "F.Fab")
		)
		(fp_line
			(start 0.4953 1.6002)
			(end -0.4953 1.6002)
			(stroke
				(width 0.1)
				(type default)
			)
			(layer "F.Fab")
		)
		(fp_line
			(start -0.4953 1.6002)
			(end -0.4953 -0.2032)
			(stroke
				(width 0.1)
				(type default)
			)
			(layer "F.Fab")
		)
		(pad "1" smd rect
			(at 0 0 90)
			(size 0.762 0.889)
			(layers "F.Cu" "F.Mask" "F.Paste")
			(net "VR_PVCCIN_CPU1_PH1_BOOT")
		)
		(pad "2" smd rect
			(at 0 1.397 90)
			(size 0.762 0.889)
			(layers "F.Cu" "F.Mask" "F.Paste")
			(net "VR_PVCCIN_CPU1_PH1_BOOT_R")
		)
		(zone
			(layer "F.Cu")
			(hatch none 0.5)
			(connect_pads
				(clearance 0)
			)
			(min_thickness 0.25)
			(keepout
				(tracks allowed)
				(vias not_allowed)
				(pads allowed)
				(copperpour not_allowed)
				(footprints allowed)
			)
			(placement
				(enabled no)
				(sheetname "")
			)
			(fill
				(thermal_gap 0.5)
				(thermal_bridge_width 0.5)
				(island_removal_mode 0)
			)
			(polygon
				(pts
					(xy 28.5115 -58.166) (xy 28.0035 -58.166) (xy 28.0035 -57.404) (xy 28.5115 -57.404)
				)
			)
		)
		(zone
			(layer "F.Cu")
			(hatch none 0.5)
			(connect_pads
				(clearance 0)
			)
			(min_thickness 0.25)
			(keepout
				(tracks not_allowed)
				(vias allowed)
				(pads allowed)
				(copperpour not_allowed)
				(footprints allowed)
			)
			(placement
				(enabled no)
				(sheetname "")
			)
			(fill
				(thermal_gap 0.5)
				(thermal_bridge_width 0.5)
				(island_removal_mode 0)
			)
			(polygon
				(pts
					(xy 28.5115 -57.404) (xy 28.5115 -58.166) (xy 28.0035 -58.166) (xy 28.0035 -57.404)
				)
			)
		)
	)
	(footprint ""
		(layer "F.Cu")
		(at 178.054 -81.026 180)
		(property "Reference" "R4D18"
			(at 0 0 180)
			(layer "F.SilkS")
			(hide yes)
			(effects
				(font
					(size 1.27 1.27)
				)
			)
		)
		(property "Value" ""
			(at 0 0 180)
			(layer "F.Fab")
			(effects
				(font
					(size 1.27 1.27)
				)
			)
		)
		(duplicate_pad_numbers_are_jumpers no)
		(fp_poly
			(pts
				(xy -0.2794 -0.1016) (xy 0.2794 -0.1016) (xy 0.2794 0.9906) (xy -0.2794 0.9906)
			)
			(stroke
				(width 0)
				(type default)
			)
			(fill no)
			(layer "F.CrtYd")
		)
		(fp_line
			(start 0.2794 0.9906)
			(end 0.2794 -0.1016)
			(stroke
				(width 0.1)
				(type default)
			)
			(layer "F.Fab")
		)
		(fp_line
			(start 0.2794 -0.1016)
			(end -0.2794 -0.1016)
			(stroke
				(width 0.1)
				(type default)
			)
			(layer "F.Fab")
		)
		(fp_line
			(start -0.2794 0.9906)
			(end 0.2794 0.9906)
			(stroke
				(width 0.1)
				(type default)
			)
			(layer "F.Fab")
		)
		(fp_line
			(start -0.2794 -0.1016)
			(end -0.2794 0.9906)
			(stroke
				(width 0.1)
				(type default)
			)
			(layer "F.Fab")
		)
		(pad "1" smd rect
			(at 0 0 180)
			(size 0.508 0.508)
			(layers "F.Cu" "F.Mask" "F.Paste")
			(net "CLK_100M_CPU0_BCLK1_DN")
		)
		(pad "2" smd rect
			(at 0 0.889 180)
			(size 0.508 0.508)
			(layers "F.Cu" "F.Mask" "F.Paste")
			(net "GND")
		)
		(zone
			(layer "F.Cu")
			(hatch none 0.5)
			(connect_pads
				(clearance 0)
			)
			(min_thickness 0.25)
			(keepout
				(tracks not_allowed)
				(vias allowed)
				(pads allowed)
				(copperpour not_allowed)
				(footprints allowed)
			)
			(placement
				(enabled no)
				(sheetname "")
			)
			(fill
				(thermal_gap 0.5)
				(thermal_bridge_width 0.5)
				(island_removal_mode 0)
			)
			(polygon
				(pts
					(xy 178.308 -81.661) (xy 177.8 -81.661) (xy 177.8 -81.28) (xy 178.308 -81.28)
				)
			)
		)
		(zone
			(layer "F.Cu")
			(hatch none 0.5)
			(connect_pads
				(clearance 0)
			)
			(min_thickness 0.25)
			(keepout
				(tracks allowed)
				(vias not_allowed)
				(pads allowed)
				(copperpour not_allowed)
				(footprints allowed)
			)
			(placement
				(enabled no)
				(sheetname "")
			)
			(fill
				(thermal_gap 0.5)
				(thermal_bridge_width 0.5)
				(island_removal_mode 0)
			)
			(polygon
				(pts
					(xy 178.308 -81.28) (xy 177.8 -81.28) (xy 177.8 -81.661) (xy 178.308 -81.661)
				)
			)
		)
	)
	(footprint ""
		(layer "F.Cu")
		(at 171.6532 -7.8232 90)
		(property "Reference" "C4G7"
			(at 0 0 90)
			(layer "F.SilkS")
			(hide yes)
			(effects
				(font
					(size 1.27 1.27)
				)
			)
		)
		(property "Value" ""
			(at 0 0 90)
			(layer "F.Fab")
			(effects
				(font
					(size 1.27 1.27)
				)
			)
		)
		(duplicate_pad_numbers_are_jumpers no)
		(fp_rect
			(start 0.3048 0.9906)
			(end -0.3048 -0.1016)
			(stroke
				(width 0)
				(type default)
			)
			(fill no)
			(layer "F.CrtYd")
		)
		(fp_line
			(start 0.3048 -0.1016)
			(end -0.3048 -0.1016)
			(stroke
				(width 0.1)
				(type default)
			)
			(layer "F.Fab")
		)
		(fp_line
			(start -0.3048 -0.1016)
			(end -0.3048 0.9906)
			(stroke
				(width 0.1)
				(type default)
			)
			(layer "F.Fab")
		)
		(fp_line
			(start 0.3048 0.9906)
			(end 0.3048 -0.1016)
			(stroke
				(width 0.1)
				(type default)
			)
			(layer "F.Fab")
		)
		(fp_line
			(start -0.3048 0.9906)
			(end 0.3048 0.9906)
			(stroke
				(width 0.1)
				(type default)
			)
			(layer "F.Fab")
		)
		(pad "1" smd rect
			(at 0 0 90)
			(size 0.508 0.508)
			(layers "F.Cu" "F.Mask" "F.Paste")
			(net "FM_PVPP_CPU1_EN")
		)
		(pad "2" smd rect
			(at 0 0.889 90)
			(size 0.508 0.508)
			(layers "F.Cu" "F.Mask" "F.Paste")
			(net "AGND_PVPP_GHJ")
		)
		(zone
			(layer "F.Cu")
			(hatch none 0.5)
			(connect_pads
				(clearance 0)
			)
			(min_thickness 0.25)
			(keepout
				(tracks not_allowed)
				(vias allowed)
				(pads allowed)
				(copperpour not_allowed)
				(footprints allowed)
			)
			(placement
				(enabled no)
				(sheetname "")
			)
			(fill
				(thermal_gap 0.5)
				(thermal_bridge_width 0.5)
				(island_removal_mode 0)
			)
			(polygon
				(pts
					(xy 172.2882 -8.0772) (xy 171.9072 -8.0772) (xy 171.9072 -7.5692) (xy 172.2882 -7.5692)
				)
			)
		)
		(zone
			(layer "F.Cu")
			(hatch none 0.5)
			(connect_pads
				(clearance 0)
			)
			(min_thickness 0.25)
			(keepout
				(tracks allowed)
				(vias not_allowed)
				(pads allowed)
				(copperpour not_allowed)
				(footprints allowed)
			)
			(placement
				(enabled no)
				(sheetname "")
			)
			(fill
				(thermal_gap 0.5)
				(thermal_bridge_width 0.5)
				(island_removal_mode 0)
			)
			(polygon
				(pts
					(xy 172.2882 -8.0772) (xy 171.9072 -8.0772) (xy 171.9072 -7.5692) (xy 172.2882 -7.5692)
				)
			)
		)
	)
)
